# S9S_MB_2U (Grand Teton) — schematic netlist excerpt (pin names and nets, part order shuffled) for the footprints in the layout excerpt that follows; sources: Cadence DE-HDL packaged netlist, KiCad conversion of 03242023_DA0F0TMBIJ0_F0T_Motherboard_J_brd_V01_OCP.brd

C3273  Q_CAP  1000PF 50V 5% EMPTY  pkg 0402  page 274 : A = PWRGD_PVCCINFAON_CPU0_R ; B = GND
PR830  Q_RES  15K 0.1% CHIP  pkg 0402LF  page 259 : A = P3V3_AUX_FB ; B = GND

(kicad_pcb
	(version 20260206)
	(generator "pcbnew")
	(generator_version "10.0")
	(general
		(thickness 1.6)
		(legacy_teardrops no)
	)
	(paper "A4")
	(title_block
		(title "03242023_DA0F0TMBIJ0_F0T_Motherboard_J_brd_V01_OCP.brd")
		(comment 1 "Grand Teton / footprints 1121-1122 of 6105")
	)
	(layers
		(0 "F.Cu" signal "TOP")
		(4 "In1.Cu" signal "GND")
		(6 "In2.Cu" signal "IN1")
		(8 "In3.Cu" signal "GND1")
		(10 "In4.Cu" signal "IN2")
		(12 "In5.Cu" signal "GND2")
		(14 "In6.Cu" signal "IN3")
		(16 "In7.Cu" signal "GND3")
		(18 "In8.Cu" signal "VCC")
		(20 "In9.Cu" signal "VCC1")
		(22 "In10.Cu" signal "GND4")
		(24 "In11.Cu" signal "IN4")
		(26 "In12.Cu" signal "GND5")
		(28 "In13.Cu" signal "IN5")
		(30 "In14.Cu" signal "GND6")
		(32 "In15.Cu" signal "IN6")
		(34 "In16.Cu" signal "GND7")
		(2 "B.Cu" signal "BOTTOM")
		(9 "F.Adhes" user "F.Adhesive")
		(11 "B.Adhes" user "B.Adhesive")
		(13 "F.Paste" user "Package Geometry/Pastemask Top")
		(15 "B.Paste" user "Package Geometry/Pastemask Bottom")
		(5 "F.SilkS" user "Ref Des/Silkscreen Top")
		(7 "B.SilkS" user "Ref Des/Silkscreen Bottom")
		(1 "F.Mask" user "Board Geometry/Soldermask Top")
		(3 "B.Mask" user "Board Geometry/Soldermask Bottom")
		(17 "Dwgs.User" user "User.Drawings")
		(19 "Cmts.User" user "User.Comments")
		(21 "Eco1.User" user "User.Eco1")
		(23 "Eco2.User" user "User.Eco2")
		(25 "Edge.Cuts" user "Board Geometry/Outline")
		(27 "Margin" user)
		(31 "F.CrtYd" user "Package Geometry/Place Bound Top")
		(29 "B.CrtYd" user "Package Geometry/Place Bound Bottom")
		(35 "F.Fab" user "Ref Des/Assembly Top")
		(33 "B.Fab" user "Ref Des/Assembly Bottom")
	)
	(footprint ""
		(layer "F.Cu")
		(at 447.589402 -77.829918 90)
		(property "Reference" "PR830"
			(at 0 0 90)
			(layer "F.SilkS")
			(hide yes)
			(effects
				(font
					(size 1.27 1.27)
				)
			)
		)
		(property "Value" ""
			(at 0 0 90)
			(layer "F.Fab")
			(effects
				(font
					(size 1.27 1.27)
				)
			)
		)
		(duplicate_pad_numbers_are_jumpers no)
		(fp_line
			(start 0.7874 -0.4064)
			(end 0.7874 0.4064)
			(stroke
				(width 0.1524)
				(type default)
			)
			(layer "F.SilkS")
		)
		(fp_line
			(start -0.7874 -0.4064)
			(end 0.7874 -0.4064)
			(stroke
				(width 0.1524)
				(type default)
			)
			(layer "F.SilkS")
		)
		(fp_line
			(start 0.7874 0.4064)
			(end -0.7874 0.4064)
			(stroke
				(width 0.1524)
				(type default)
			)
			(layer "F.SilkS")
		)
		(fp_line
			(start -0.7874 0.4064)
			(end -0.7874 -0.4064)
			(stroke
				(width 0.1524)
				(type default)
			)
			(layer "F.SilkS")
		)
		(fp_line
			(start -0.12065 -0.305054)
			(end -0.12065 -0.2794)
			(stroke
				(width 0.1)
				(type default)
			)
			(layer "F.Fab")
		)
		(fp_line
			(start -0.67945 -0.305054)
			(end -0.12065 -0.305054)
			(stroke
				(width 0.1)
				(type default)
			)
			(layer "F.Fab")
		)
		(fp_line
			(start 0.67945 -0.3048)
			(end 0.67945 0.3048)
			(stroke
				(width 0.1)
				(type default)
			)
			(layer "F.Fab")
		)
		(fp_line
			(start 0.12065 -0.3048)
			(end 0.67945 -0.3048)
			(stroke
				(width 0.1)
				(type default)
			)
			(layer "F.Fab")
		)
		(fp_line
			(start 0.12065 -0.2794)
			(end 0.12065 -0.3048)
			(stroke
				(width 0.1)
				(type default)
			)
			(layer "F.Fab")
		)
		(fp_line
			(start -0.12065 -0.2794)
			(end 0.12065 -0.2794)
			(stroke
				(width 0.1)
				(type default)
			)
			(layer "F.Fab")
		)
		(fp_line
			(start 0.120396 0.2794)
			(end -0.12065 0.2794)
			(stroke
				(width 0.1)
				(type default)
			)
			(layer "F.Fab")
		)
		(fp_line
			(start -0.12065 0.2794)
			(end -0.12065 0.3048)
			(stroke
				(width 0.1)
				(type default)
			)
			(layer "F.Fab")
		)
		(fp_line
			(start 0.67945 0.3048)
			(end 0.120396 0.3048)
			(stroke
				(width 0.1)
				(type default)
			)
			(layer "F.Fab")
		)
		(fp_line
			(start 0.120396 0.3048)
			(end 0.120396 0.2794)
			(stroke
				(width 0.1)
				(type default)
			)
			(layer "F.Fab")
		)
		(fp_line
			(start -0.12065 0.3048)
			(end -0.67945 0.3048)
			(stroke
				(width 0.1)
				(type default)
			)
			(layer "F.Fab")
		)
		(fp_line
			(start -0.67945 0.3048)
			(end -0.67945 -0.305054)
			(stroke
				(width 0.1)
				(type default)
			)
			(layer "F.Fab")
		)
		(pad "1" smd circle
			(at -0.40005 0 90)
			(size 0 0)
			(layers "F.Cu" "F.Mask" "F.Paste")
			(net "P3V3_AUX_FB")
		)
		(pad "2" smd circle
			(at 0.40005 0 90)
			(size 0 0)
			(layers "F.Cu" "F.Mask" "F.Paste")
			(net "GND")
		)
	)
	(footprint ""
		(layer "F.Cu")
		(at 430.600104 -133.478778)
		(property "Reference" "C3273"
			(at 0 0 0)
			(layer "F.SilkS")
			(hide yes)
			(effects
				(font
					(size 1.27 1.27)
				)
			)
		)
		(property "Value" ""
			(at 0 0 0)
			(layer "F.Fab")
			(effects
				(font
					(size 1.27 1.27)
				)
			)
		)
		(duplicate_pad_numbers_are_jumpers no)
		(fp_line
			(start -0.7874 -0.4064)
			(end 0.7874 -0.4064)
			(stroke
				(width 0.1524)
				(type default)
			)
			(layer "F.SilkS")
		)
		(fp_line
			(start -0.7874 0.4064)
			(end -0.7874 -0.4064)
			(stroke
				(width 0.1524)
				(type default)
			)
			(layer "F.SilkS")
		)
		(fp_line
			(start 0.7874 -0.4064)
			(end 0.7874 0.4064)
			(stroke
				(width 0.1524)
				(type default)
			)
			(layer "F.SilkS")
		)
		(fp_line
			(start 0.7874 0.4064)
			(end -0.7874 0.4064)
			(stroke
				(width 0.1524)
				(type default)
			)
			(layer "F.SilkS")
		)
		(fp_line
			(start -0.67945 -0.305054)
			(end -0.12065 -0.305054)
			(stroke
				(width 0.1)
				(type default)
			)
			(layer "F.Fab")
		)
		(fp_line
			(start -0.67945 0.3048)
			(end -0.67945 -0.305054)
			(stroke
				(width 0.1)
				(type default)
			)
			(layer "F.Fab")
		)
		(fp_line
			(start -0.12065 -0.305054)
			(end -0.12065 -0.2794)
			(stroke
				(width 0.1)
				(type default)
			)
			(layer "F.Fab")
		)
		(fp_line
			(start -0.12065 -0.2794)
			(end 0.12065 -0.2794)
			(stroke
				(width 0.1)
				(type default)
			)
			(layer "F.Fab")
		)
		(fp_line
			(start -0.12065 0.2794)
			(end -0.12065 0.3048)
			(stroke
				(width 0.1)
				(type default)
			)
			(layer "F.Fab")
		)
		(fp_line
			(start -0.12065 0.3048)
			(end -0.67945 0.3048)
			(stroke
				(width 0.1)
				(type default)
			)
			(layer "F.Fab")
		)
		(fp_line
			(start 0.120396 0.2794)
			(end -0.12065 0.2794)
			(stroke
				(width 0.1)
				(type default)
			)
			(layer "F.Fab")
		)
		(fp_line
			(start 0.120396 0.3048)
			(end 0.120396 0.2794)
			(stroke
				(width 0.1)
				(type default)
			)
			(layer "F.Fab")
		)
		(fp_line
			(start 0.12065 -0.3048)
			(end 0.67945 -0.3048)
			(stroke
				(width 0.1)
				(type default)
			)
			(layer "F.Fab")
		)
		(fp_line
			(start 0.12065 -0.2794)
			(end 0.12065 -0.3048)
			(stroke
				(width 0.1)
				(type default)
			)
			(layer "F.Fab")
		)
		(fp_line
			(start 0.67945 -0.3048)
			(end 0.67945 0.3048)
			(stroke
				(width 0.1)
				(type default)
			)
			(layer "F.Fab")
		)
		(fp_line
			(start 0.67945 0.3048)
			(end 0.120396 0.3048)
			(stroke
				(width 0.1)
				(type default)
			)
			(layer "F.Fab")
		)
		(pad "1" smd circle
			(at -0.40005 0)
			(size 0 0)
			(layers "F.Cu" "F.Mask" "F.Paste")
			(net "PWRGD_PVCCINFAON_CPU0_R")
		)
		(pad "2" smd circle
			(at 0.40005 0)
			(size 0 0)
			(layers "F.Cu" "F.Mask" "F.Paste")
			(net "GND")
		)
	)
)
